(kicad_pcb
	(version 20260206)
	(generator "pcbnew")
	(generator_version "10.0")
	(general
		(thickness 1.6)
		(legacy_teardrops no)
	)
	(paper "A4")
	(title_block
		(title "timecard-production-celestica-r4006 — R4006-B0001-02_R01.brd")
		(comment 1 "Time Appliance Project (Time Card) / footprints 155-159 of 1113")
	)
	(layers
		(0 "F.Cu" signal "TOP")
		(4 "In1.Cu" signal "L02_GND1")
		(6 "In2.Cu" signal "L03_SIG1")
		(8 "In3.Cu" signal "L04_GND2")
		(10 "In4.Cu" signal "L05_VCC1")
		(12 "In5.Cu" signal "L06_VCC2")
		(14 "In6.Cu" signal "L07_GND3")
		(16 "In7.Cu" signal "L08_SIG2")
		(18 "In8.Cu" signal "L09_GND4")
		(2 "B.Cu" signal "BOTTOM")
		(9 "F.Adhes" user "F.Adhesive")
		(11 "B.Adhes" user "B.Adhesive")
		(13 "F.Paste" user "Package Geometry/Pastemask Top")
		(15 "B.Paste" user "Package Geometry/Pastemask Bottom")
		(5 "F.SilkS" user "Ref Des/Silkscreen Top")
		(7 "B.SilkS" user "Ref Des/Silkscreen Bottom")
		(1 "F.Mask" user "Board Geometry/Soldermask Top")
		(3 "B.Mask" user "Board Geometry/Soldermask Bottom")
		(17 "Dwgs.User" user "User.Drawings")
		(19 "Cmts.User" user "User.Comments")
		(21 "Eco1.User" user "User.Eco1")
		(23 "Eco2.User" user "User.Eco2")
		(25 "Edge.Cuts" user "Board Geometry/Outline")
		(27 "Margin" user)
		(31 "F.CrtYd" user "Package Geometry/Place Bound Top")
		(29 "B.CrtYd" user "Package Geometry/Place Bound Bottom")
		(35 "F.Fab" user "Ref Des/Assembly Top")
		(33 "B.Fab" user "Ref Des/Assembly Bottom")
	)
	(footprint ""
		(layer "F.Cu")
		(at 83.185 -54.991)
		(property "Reference" "R290"
			(at -9.398 -18.62963 0)
			(unlocked yes)
			(layer "F.SilkS")
			(effects
				(font
					(size 0.7874 0.5842)
					(thickness 0.1524)
				)
			)
		)
		(property "Value" "VAL*"
			(at 0.02032 2.13233 0)
			(unlocked yes)
			(layer "F.Fab")
			(hide yes)
			(effects
				(font
					(size 0.7874 0.5842)
					(thickness 0.1524)
				)
			)
		)
		(property "Tolerance" "TOL*"
			(at 0.044704 3.05435 0)
			(unlocked yes)
			(layer "Cmts.User")
			(hide yes)
			(effects
				(font
					(size 0.7874 0.5842)
					(thickness 0.1524)
				)
			)
		)
		(property "User Part Number" "PARTNUM*"
			(at 0.02032 4.024884 0)
			(unlocked yes)
			(layer "Cmts.User")
			(hide yes)
			(effects
				(font
					(size 0.7874 0.5842)
					(thickness 0.1524)
				)
			)
		)
		(property "Device Type" "RESISTOR-G155-14701-01,4.7KOHMA"
			(at 0.008382 1.210564 0)
			(unlocked yes)
			(layer "F.Fab")
			(hide yes)
			(effects
				(font
					(size 0.7874 0.5842)
					(thickness 0.1524)
				)
			)
		)
		(duplicate_pad_numbers_are_jumpers no)
		(fp_line
			(start -1.143 -0.5588)
			(end -1.143 0.5588)
			(stroke
				(width 0.1)
				(type default)
			)
			(layer "F.SilkS")
		)
		(fp_line
			(start -1.143 0.5588)
			(end 1.143 0.5588)
			(stroke
				(width 0.1)
				(type default)
			)
			(layer "F.SilkS")
		)
		(fp_line
			(start 1.143 -0.5588)
			(end -1.143 -0.5588)
			(stroke
				(width 0.1)
				(type default)
			)
			(layer "F.SilkS")
		)
		(fp_line
			(start 1.143 0.5588)
			(end 1.143 -0.5588)
			(stroke
				(width 0.1)
				(type default)
			)
			(layer "F.SilkS")
		)
		(fp_rect
			(start -1.143 -0.5588)
			(end 1.143 0.5588)
			(stroke
				(width 0)
				(type default)
			)
			(fill no)
			(layer "F.CrtYd")
		)
		(fp_line
			(start -0.508 -0.3048)
			(end -0.508 0.3048)
			(stroke
				(width 0.1)
				(type default)
			)
			(layer "F.Fab")
		)
		(fp_line
			(start -0.508 0.3048)
			(end 0.508 0.3048)
			(stroke
				(width 0.1)
				(type default)
			)
			(layer "F.Fab")
		)
		(fp_line
			(start 0.508 -0.3048)
			(end -0.508 -0.3048)
			(stroke
				(width 0.1)
				(type default)
			)
			(layer "F.Fab")
		)
		(fp_line
			(start 0.508 0.3048)
			(end 0.508 -0.3048)
			(stroke
				(width 0.1)
				(type default)
			)
			(layer "F.Fab")
		)
		(pad "1" smd rect
			(at -0.5334 0)
			(size 0.7112 0.6096)
			(layers "F.Cu" "F.Mask" "F.Paste")
			(net "XP3R3V_FPGA")
		)
		(pad "2" smd rect
			(at 0.5334 0)
			(size 0.7112 0.6096)
			(layers "F.Cu" "F.Mask" "F.Paste")
			(net "BNO080_SA0")
		)
		(zone
			(layer "F.Cu")
			(hatch none 0.5)
			(connect_pads
				(clearance 0)
			)
			(min_thickness 0.25)
			(keepout
				(tracks allowed)
				(vias not_allowed)
				(pads allowed)
				(copperpour not_allowed)
				(footprints allowed)
			)
			(placement
				(enabled no)
				(sheetname "")
			)
			(fill
				(thermal_gap 0.5)
				(thermal_bridge_width 0.5)
				(island_removal_mode 0)
			)
			(polygon
				(pts
					(xy 83.1088 -55.2958) (xy 83.1088 -54.6862) (xy 83.2612 -54.6862) (xy 83.2612 -55.2958)
				)
			)
		)
	)
	(footprint ""
		(layer "F.Cu")
		(at 46.736 -81.026)
		(property "Reference" "C298"
			(at 3.81 0.16637 0)
			(unlocked yes)
			(layer "F.SilkS")
			(effects
				(font
					(size 0.7874 0.5842)
					(thickness 0.1524)
				)
			)
		)
		(property "Value" "VAL*"
			(at 0.0762 2.067306 0)
			(unlocked yes)
			(layer "F.Fab")
			(hide yes)
			(effects
				(font
					(size 0.7874 0.5842)
					(thickness 0.1524)
				)
			)
		)
		(property "Tolerance" "TOL*"
			(at 0.0762 3.032506 0)
			(unlocked yes)
			(layer "Cmts.User")
			(hide yes)
			(effects
				(font
					(size 0.7874 0.5842)
					(thickness 0.1524)
				)
			)
		)
		(property "User Part Number" "PARTNUM*"
			(at 0.1016 4.023106 0)
			(unlocked yes)
			(layer "Cmts.User")
			(hide yes)
			(effects
				(font
					(size 0.7874 0.5842)
					(thickness 0.1524)
				)
			)
		)
		(property "Device Type" "CAPACITOR-G105-0B104-EK,0.1UF,A"
			(at 0.0508 1.127506 0)
			(unlocked yes)
			(layer "F.Fab")
			(hide yes)
			(effects
				(font
					(size 0.7874 0.5842)
					(thickness 0.1524)
				)
			)
		)
		(duplicate_pad_numbers_are_jumpers no)
		(fp_line
			(start -1.143 -0.5588)
			(end -1.143 0.5588)
			(stroke
				(width 0.1)
				(type default)
			)
			(layer "F.SilkS")
		)
		(fp_line
			(start -1.143 0.5588)
			(end 1.143 0.5588)
			(stroke
				(width 0.1)
				(type default)
			)
			(layer "F.SilkS")
		)
		(fp_line
			(start 1.143 -0.5588)
			(end -1.143 -0.5588)
			(stroke
				(width 0.1)
				(type default)
			)
			(layer "F.SilkS")
		)
		(fp_line
			(start 1.143 0.5588)
			(end 1.143 -0.5588)
			(stroke
				(width 0.1)
				(type default)
			)
			(layer "F.SilkS")
		)
		(fp_poly
			(pts
				(xy -1.143 0.5588) (xy 1.143 0.5588) (xy 1.143 -0.5588) (xy -1.143 -0.5588)
			)
			(stroke
				(width 0)
				(type default)
			)
			(fill no)
			(layer "F.CrtYd")
		)
		(fp_line
			(start -0.508 -0.3048)
			(end -0.508 0.3048)
			(stroke
				(width 0.1)
				(type default)
			)
			(layer "F.Fab")
		)
		(fp_line
			(start -0.508 0.3048)
			(end 0.508 0.3048)
			(stroke
				(width 0.1)
				(type default)
			)
			(layer "F.Fab")
		)
		(fp_line
			(start 0.508 -0.3048)
			(end -0.508 -0.3048)
			(stroke
				(width 0.1)
				(type default)
			)
			(layer "F.Fab")
		)
		(fp_line
			(start 0.508 0.3048)
			(end 0.508 -0.3048)
			(stroke
				(width 0.1)
				(type default)
			)
			(layer "F.Fab")
		)
		(pad "1" smd rect
			(at -0.5334 0)
			(size 0.7112 0.6096)
			(layers "F.Cu" "F.Mask" "F.Paste")
			(net "UNNAMED_525_CAPACITOR_I7_1")
		)
		(pad "2" smd rect
			(at 0.5334 0)
			(size 0.7112 0.6096)
			(layers "F.Cu" "F.Mask" "F.Paste")
			(net "SG")
		)
		(zone
			(layer "F.Cu")
			(hatch none 0.5)
			(connect_pads
				(clearance 0)
			)
			(min_thickness 0.25)
			(keepout
				(tracks allowed)
				(vias not_allowed)
				(pads allowed)
				(copperpour not_allowed)
				(footprints allowed)
			)
			(placement
				(enabled no)
				(sheetname "")
			)
			(fill
				(thermal_gap 0.5)
				(thermal_bridge_width 0.5)
				(island_removal_mode 0)
			)
			(polygon
				(pts
					(xy 46.6598 -80.7212) (xy 46.8122 -80.7212) (xy 46.8122 -81.3308) (xy 46.6598 -81.3308)
				)
			)
		)
		(zone
			(layer "F.Cu")
			(hatch none 0.5)
			(connect_pads
				(clearance 0)
			)
			(min_thickness 0.25)
			(keepout
				(tracks not_allowed)
				(vias allowed)
				(pads allowed)
				(copperpour not_allowed)
				(footprints allowed)
			)
			(placement
				(enabled no)
				(sheetname "")
			)
			(fill
				(thermal_gap 0.5)
				(thermal_bridge_width 0.5)
				(island_removal_mode 0)
			)
			(polygon
				(pts
					(xy 46.6598 -80.7212) (xy 46.8122 -80.7212) (xy 46.8122 -81.3308) (xy 46.6598 -81.3308)
				)
			)
		)
	)
	(footprint ""
		(layer "F.Cu")
		(at 111.125 -101.981)
		(property "Reference" "R323"
			(at 3.175 -3.13563 0)
			(unlocked yes)
			(layer "F.SilkS")
			(effects
				(font
					(size 0.7874 0.5842)
					(thickness 0.1524)
				)
			)
		)
		(property "Value" "VAL*"
			(at 0.02032 2.13233 0)
			(unlocked yes)
			(layer "F.Fab")
			(hide yes)
			(effects
				(font
					(size 0.7874 0.5842)
					(thickness 0.1524)
				)
			)
		)
		(property "Tolerance" "TOL*"
			(at 0.044704 3.05435 0)
			(unlocked yes)
			(layer "Cmts.User")
			(hide yes)
			(effects
				(font
					(size 0.7874 0.5842)
					(thickness 0.1524)
				)
			)
		)
		(property "User Part Number" "PARTNUM*"
			(at 0.02032 4.024884 0)
			(unlocked yes)
			(layer "Cmts.User")
			(hide yes)
			(effects
				(font
					(size 0.7874 0.5842)
					(thickness 0.1524)
				)
			)
		)
		(property "Device Type" "RESISTOR-G155-14701-01,4.7KOHMA"
			(at 0.008382 1.210564 0)
			(unlocked yes)
			(layer "F.Fab")
			(hide yes)
			(effects
				(font
					(size 0.7874 0.5842)
					(thickness 0.1524)
				)
			)
		)
		(duplicate_pad_numbers_are_jumpers no)
		(fp_line
			(start -1.143 -0.5588)
			(end -1.143 0.5588)
			(stroke
				(width 0.1)
				(type default)
			)
			(layer "F.SilkS")
		)
		(fp_line
			(start -1.143 0.5588)
			(end 1.143 0.5588)
			(stroke
				(width 0.1)
				(type default)
			)
			(layer "F.SilkS")
		)
		(fp_line
			(start 1.143 -0.5588)
			(end -1.143 -0.5588)
			(stroke
				(width 0.1)
				(type default)
			)
			(layer "F.SilkS")
		)
		(fp_line
			(start 1.143 0.5588)
			(end 1.143 -0.5588)
			(stroke
				(width 0.1)
				(type default)
			)
			(layer "F.SilkS")
		)
		(fp_poly
			(pts
				(xy -1.143 0.5588) (xy 1.143 0.5588) (xy 1.143 -0.5588) (xy -1.143 -0.5588)
			)
			(stroke
				(width 0)
				(type default)
			)
			(fill no)
			(layer "F.CrtYd")
		)
		(fp_line
			(start -0.508 -0.3048)
			(end -0.508 0.3048)
			(stroke
				(width 0.1)
				(type default)
			)
			(layer "F.Fab")
		)
		(fp_line
			(start -0.508 0.3048)
			(end 0.508 0.3048)
			(stroke
				(width 0.1)
				(type default)
			)
			(layer "F.Fab")
		)
		(fp_line
			(start 0.508 -0.3048)
			(end -0.508 -0.3048)
			(stroke
				(width 0.1)
				(type default)
			)
			(layer "F.Fab")
		)
		(fp_line
			(start 0.508 0.3048)
			(end 0.508 -0.3048)
			(stroke
				(width 0.1)
				(type default)
			)
			(layer "F.Fab")
		)
		(pad "1" smd rect
			(at -0.5334 0)
			(size 0.7112 0.6096)
			(layers "F.Cu" "F.Mask" "F.Paste")
			(net "UNNAMED_14_IS32FL3207QWLA3TRQ_1")
		)
		(pad "2" smd rect
			(at 0.5334 0)
			(size 0.7112 0.6096)
			(layers "F.Cu" "F.Mask" "F.Paste")
			(net "SG")
		)
		(zone
			(layer "F.Cu")
			(hatch none 0.5)
			(connect_pads
				(clearance 0)
			)
			(min_thickness 0.25)
			(keepout
				(tracks allowed)
				(vias not_allowed)
				(pads allowed)
				(copperpour not_allowed)
				(footprints allowed)
			)
			(placement
				(enabled no)
				(sheetname "")
			)
			(fill
				(thermal_gap 0.5)
				(thermal_bridge_width 0.5)
				(island_removal_mode 0)
			)
			(polygon
				(pts
					(xy 111.0488 -101.6762) (xy 111.2012 -101.6762) (xy 111.2012 -102.2858) (xy 111.0488 -102.2858)
				)
			)
		)
		(zone
			(layer "F.Cu")
			(hatch none 0.5)
			(connect_pads
				(clearance 0)
			)
			(min_thickness 0.25)
			(keepout
				(tracks not_allowed)
				(vias allowed)
				(pads allowed)
				(copperpour not_allowed)
				(footprints allowed)
			)
			(placement
				(enabled no)
				(sheetname "")
			)
			(fill
				(thermal_gap 0.5)
				(thermal_bridge_width 0.5)
				(island_removal_mode 0)
			)
			(polygon
				(pts
					(xy 111.0488 -101.6762) (xy 111.2012 -101.6762) (xy 111.2012 -102.2858) (xy 111.0488 -102.2858)
				)
			)
		)
	)
	(footprint ""
		(layer "F.Cu")
		(at 142.6464 -90.6526)
		(property "Reference" "C2"
			(at -0.6604 1.15697 0)
			(unlocked yes)
			(layer "F.SilkS")
			(effects
				(font
					(size 0.7874 0.5842)
					(thickness 0.1524)
				)
			)
		)
		(property "Value" "VAL*"
			(at 0.0762 2.067306 0)
			(unlocked yes)
			(layer "F.Fab")
			(hide yes)
			(effects
				(font
					(size 0.7874 0.5842)
					(thickness 0.1524)
				)
			)
		)
		(property "Device Type" "CAPACITOR-G105-0B104-EK,0.1UF,A"
			(at 0.0508 1.127506 0)
			(unlocked yes)
			(layer "F.Fab")
			(hide yes)
			(effects
				(font
					(size 0.7874 0.5842)
					(thickness 0.1524)
				)
			)
		)
		(property "User Part Number" "PARTNUM*"
			(at 0.1016 4.023106 0)
			(unlocked yes)
			(layer "Cmts.User")
			(hide yes)
			(effects
				(font
					(size 0.7874 0.5842)
					(thickness 0.1524)
				)
			)
		)
		(property "Tolerance" "TOL*"
			(at 0.0762 3.032506 0)
			(unlocked yes)
			(layer "Cmts.User")
			(hide yes)
			(effects
				(font
					(size 0.7874 0.5842)
					(thickness 0.1524)
				)
			)
		)
		(duplicate_pad_numbers_are_jumpers no)
		(fp_line
			(start -1.143 -0.5588)
			(end -1.143 0.5588)
			(stroke
				(width 0.1)
				(type default)
			)
			(layer "F.SilkS")
		)
		(fp_line
			(start -1.143 0.5588)
			(end 1.143 0.5588)
			(stroke
				(width 0.1)
				(type default)
			)
			(layer "F.SilkS")
		)
		(fp_line
			(start 1.143 -0.5588)
			(end -1.143 -0.5588)
			(stroke
				(width 0.1)
				(type default)
			)
			(layer "F.SilkS")
		)
		(fp_line
			(start 1.143 0.5588)
			(end 1.143 -0.5588)
			(stroke
				(width 0.1)
				(type default)
			)
			(layer "F.SilkS")
		)
		(fp_rect
			(start -1.143 0.5588)
			(end 1.143 -0.5588)
			(stroke
				(width 0)
				(type default)
			)
			(fill no)
			(layer "F.CrtYd")
		)
		(fp_line
			(start -0.508 -0.3048)
			(end -0.508 0.3048)
			(stroke
				(width 0.1)
				(type default)
			)
			(layer "F.Fab")
		)
		(fp_line
			(start -0.508 0.3048)
			(end 0.508 0.3048)
			(stroke
				(width 0.1)
				(type default)
			)
			(layer "F.Fab")
		)
		(fp_line
			(start 0.508 -0.3048)
			(end -0.508 -0.3048)
			(stroke
				(width 0.1)
				(type default)
			)
			(layer "F.Fab")
		)
		(fp_line
			(start 0.508 0.3048)
			(end 0.508 -0.3048)
			(stroke
				(width 0.1)
				(type default)
			)
			(layer "F.Fab")
		)
		(pad "1" smd rect
			(at -0.5334 0)
			(size 0.7112 0.6096)
			(layers "F.Cu" "F.Mask" "F.Paste")
			(net "XP12R0V_IN")
		)
		(pad "2" smd rect
			(at 0.5334 0)
			(size 0.7112 0.6096)
			(layers "F.Cu" "F.Mask" "F.Paste")
			(net "SG")
		)
		(zone
			(layer "F.Cu")
			(hatch none 0.5)
			(connect_pads
				(clearance 0)
			)
			(min_thickness 0.25)
			(keepout
				(tracks allowed)
				(vias not_allowed)
				(pads allowed)
				(copperpour not_allowed)
				(footprints allowed)
			)
			(placement
				(enabled no)
				(sheetname "")
			)
			(fill
				(thermal_gap 0.5)
				(thermal_bridge_width 0.5)
				(island_removal_mode 0)
			)
			(polygon
				(pts
					(xy 142.5702 -90.3478) (xy 142.7226 -90.3478) (xy 142.7226 -90.9574) (xy 142.5702 -90.9574)
				)
			)
		)
	)
	(footprint ""
		(layer "F.Cu")
		(at 102.997 -26.67 90)
		(property "Reference" "C253"
			(at 0.508 -2.24663 90)
			(unlocked yes)
			(layer "F.SilkS")
			(effects
				(font
					(size 0.7874 0.5842)
					(thickness 0.1524)
				)
			)
		)
		(property "Value" "VAL*"
			(at 0.0762 2.067306 90)
			(unlocked yes)
			(layer "F.Fab")
			(hide yes)
			(effects
				(font
					(size 0.7874 0.5842)
					(thickness 0.1524)
				)
			)
		)
		(property "Tolerance" "TOL*"
			(at 0.0762 3.032506 90)
			(unlocked yes)
			(layer "Cmts.User")
			(hide yes)
			(effects
				(font
					(size 0.7874 0.5842)
					(thickness 0.1524)
				)
			)
		)
		(property "User Part Number" "PARTNUM*"
			(at 0.1016 4.023106 90)
			(unlocked yes)
			(layer "Cmts.User")
			(hide yes)
			(effects
				(font
					(size 0.7874 0.5842)
					(thickness 0.1524)
				)
			)
		)
		(property "Device Type" "CAPACITOR-G105-0B104-CK,0.1UF,A"
			(at 0.0508 1.127506 90)
			(unlocked yes)
			(layer "F.Fab")
			(hide yes)
			(effects
				(font
					(size 0.7874 0.5842)
					(thickness 0.1524)
				)
			)
		)
		(duplicate_pad_numbers_are_jumpers no)
		(fp_line
			(start 1.143 -0.5588)
			(end -1.143 -0.5588)
			(stroke
				(width 0.1)
				(type default)
			)
			(layer "F.SilkS")
		)
		(fp_line
			(start -1.143 -0.5588)
			(end -1.143 0.5588)
			(stroke
				(width 0.1)
				(type default)
			)
			(layer "F.SilkS")
		)
		(fp_line
			(start 1.143 0.5588)
			(end 1.143 -0.5588)
			(stroke
				(width 0.1)
				(type default)
			)
			(layer "F.SilkS")
		)
		(fp_line
			(start -1.143 0.5588)
			(end 1.143 0.5588)
			(stroke
				(width 0.1)
				(type default)
			)
			(layer "F.SilkS")
		)
		(fp_rect
			(start -1.143 -0.5588)
			(end 1.143 0.5588)
			(stroke
				(width 0)
				(type default)
			)
			(fill no)
			(layer "F.CrtYd")
		)
		(fp_line
			(start 0.508 -0.3048)
			(end -0.508 -0.3048)
			(stroke
				(width 0.1)
				(type default)
			)
			(layer "F.Fab")
		)
		(fp_line
			(start -0.508 -0.3048)
			(end -0.508 0.3048)
			(stroke
				(width 0.1)
				(type default)
			)
			(layer "F.Fab")
		)
		(fp_line
			(start 0.508 0.3048)
			(end 0.508 -0.3048)
			(stroke
				(width 0.1)
				(type default)
			)
			(layer "F.Fab")
		)
		(fp_line
			(start -0.508 0.3048)
			(end 0.508 0.3048)
			(stroke
				(width 0.1)
				(type default)
			)
			(layer "F.Fab")
		)
		(pad "1" smd rect
			(at -0.5334 0 90)
			(size 0.7112 0.6096)
			(layers "F.Cu" "F.Mask" "F.Paste")
			(net "OSC_125M_CLKP")
		)
		(pad "2" smd rect
			(at 0.5334 0 90)
			(size 0.7112 0.6096)
			(layers "F.Cu" "F.Mask" "F.Paste")
			(net "MHZ125CLKP_CLKIN")
		)
		(zone
			(layer "F.Cu")
			(hatch none 0.5)
			(connect_pads
				(clearance 0)
			)
			(min_thickness 0.25)
			(keepout
				(tracks allowed)
				(vias not_allowed)
				(pads allowed)
				(copperpour not_allowed)
				(footprints allowed)
			)
			(placement
				(enabled no)
				(sheetname "")
			)
			(fill
				(thermal_gap 0.5)
				(thermal_bridge_width 0.5)
				(island_removal_mode 0)
			)
			(polygon
				(pts
					(xy 102.6922 -26.5938) (xy 103.3018 -26.5938) (xy 103.3018 -26.7462) (xy 102.6922 -26.7462)
				)
			)
		)
	)
)
